(kicad_pcb
	(version 20260206)
	(generator "pcbnew")
	(generator_version "10.0")
	(general
		(thickness 1.6)
		(legacy_teardrops no)
	)
	(paper "A4")
	(title_block
		(title "Bryce Canyon_IOM_IOC_16318-2_OCP.brd")
		(comment 1 "Bryce Canyon / footprints 974-980 of 1605")
	)
	(layers
		(0 "F.Cu" signal "TOP")
		(4 "In1.Cu" signal "L2GND")
		(6 "In2.Cu" signal "L3")
		(8 "In3.Cu" signal "L4VCC")
		(10 "In4.Cu" signal "L5VCC")
		(12 "In5.Cu" signal "L6")
		(14 "In6.Cu" signal "L7GND")
		(2 "B.Cu" signal "BOTTOM")
		(9 "F.Adhes" user "F.Adhesive")
		(11 "B.Adhes" user "B.Adhesive")
		(13 "F.Paste" user "Package Geometry/Pastemask Top")
		(15 "B.Paste" user "Package Geometry/Pastemask Bottom")
		(5 "F.SilkS" user "Ref Des/Silkscreen Top")
		(7 "B.SilkS" user "Ref Des/Silkscreen Bottom")
		(1 "F.Mask" user "Board Geometry/Soldermask Top")
		(3 "B.Mask" user "Board Geometry/Soldermask Bottom")
		(17 "Dwgs.User" user "User.Drawings")
		(19 "Cmts.User" user "User.Comments")
		(21 "Eco1.User" user "User.Eco1")
		(23 "Eco2.User" user "User.Eco2")
		(25 "Edge.Cuts" user "Board Geometry/Outline")
		(27 "Margin" user)
		(31 "F.CrtYd" user "Package Geometry/Place Bound Top")
		(29 "B.CrtYd" user "Package Geometry/Place Bound Bottom")
		(35 "F.Fab" user "Ref Des/Assembly Top")
		(33 "B.Fab" user "Ref Des/Assembly Bottom")
	)
	(footprint ""
		(layer "B.Cu")
		(at 193.7258 -68.326 90)
		(property "Reference" "C427"
			(at 0 0 90)
			(layer "B.SilkS")
			(hide yes)
			(effects
				(font
					(size 1.27 1.27)
				)
				(justify mirror)
			)
		)
		(property "Value" "SC1KP50V2KX-1GP"
			(at -1.1811 -2.7051 90)
			(unlocked yes)
			(layer "B.Fab")
			(hide yes)
			(effects
				(font
					(size 1.016 1.016)
					(thickness 0.1524)
				)
				(justify mirror)
			)
		)
		(property "Device Type" "C402H22"
			(at -1.1811 -4.2291 90)
			(unlocked yes)
			(layer "B.Fab")
			(hide yes)
			(effects
				(font
					(size 1.016 1.016)
					(thickness 0.1524)
				)
				(justify mirror)
			)
		)
		(duplicate_pad_numbers_are_jumpers no)
		(fp_rect
			(start 0.4318 0.9525)
			(end -0.4318 -0.9525)
			(stroke
				(width 0)
				(type default)
			)
			(fill no)
			(layer "B.CrtYd")
		)
		(fp_rect
			(start 0.4318 0.9525)
			(end -0.4318 -0.9525)
			(stroke
				(width 0)
				(type default)
			)
			(fill no)
			(layer "B.Fab")
		)
		(pad "1" smd custom
			(at 0 -0.4445 270)
			(size 0.1524 0.1524)
			(layers "B.Cu" "B.Mask" "B.Paste")
			(net "P0V975")
			(options
				(clearance outline)
				(anchor circle)
			)
			(primitives
				(gr_poly
					(pts
						(arc
							(start 0.3048 0.2032)
							(mid 0.275042 0.275042)
							(end 0.2032 0.3048)
						)
						(arc
							(start -0.2032 0.3048)
							(mid -0.275042 0.275042)
							(end -0.3048 0.2032)
						)
						(arc
							(start -0.3048 -0.2032)
							(mid -0.275042 -0.275042)
							(end -0.2032 -0.3048)
						)
						(arc
							(start 0.2032 -0.3048)
							(mid 0.275042 -0.275042)
							(end 0.3048 -0.2032)
						)
					)
					(width 0)
					(fill yes)
				)
			)
		)
		(pad "2" smd custom
			(at 0 0.4445 270)
			(size 0.1524 0.1524)
			(layers "B.Cu" "B.Mask" "B.Paste")
			(net "GND")
			(options
				(clearance outline)
				(anchor circle)
			)
			(primitives
				(gr_poly
					(pts
						(arc
							(start 0.3048 0.2032)
							(mid 0.275042 0.275042)
							(end 0.2032 0.3048)
						)
						(arc
							(start -0.2032 0.3048)
							(mid -0.275042 0.275042)
							(end -0.3048 0.2032)
						)
						(arc
							(start -0.3048 -0.2032)
							(mid -0.275042 -0.275042)
							(end -0.2032 -0.3048)
						)
						(arc
							(start 0.2032 -0.3048)
							(mid 0.275042 -0.275042)
							(end 0.3048 -0.2032)
						)
					)
					(width 0)
					(fill yes)
				)
			)
		)
	)
	(footprint ""
		(layer "B.Cu")
		(at 179.47132 -80.98536)
		(property "Reference" "R686"
			(at 0 0 0)
			(layer "B.SilkS")
			(hide yes)
			(effects
				(font
					(size 1.27 1.27)
				)
				(justify mirror)
			)
		)
		(property "Value" "D51R3F-2-GP"
			(at 0.0254 -2.5146 0)
			(unlocked yes)
			(layer "B.Fab")
			(hide yes)
			(effects
				(font
					(size 1.016 1.016)
					(thickness 0.1524)
				)
				(justify mirror)
			)
		)
		(property "Device Type" "R603H22"
			(at 0.0254 -4.0386 0)
			(unlocked yes)
			(layer "B.Fab")
			(hide yes)
			(effects
				(font
					(size 1.016 1.016)
					(thickness 0.1524)
				)
				(justify mirror)
			)
		)
		(duplicate_pad_numbers_are_jumpers no)
		(fp_line
			(start -0.2032 0)
			(end -0.4826 0)
			(stroke
				(width 0.2032)
				(type default)
			)
			(layer "B.SilkS")
		)
		(fp_line
			(start 0.4826 0)
			(end 0.2032 0)
			(stroke
				(width 0.2032)
				(type default)
			)
			(layer "B.SilkS")
		)
		(fp_rect
			(start 0.5842 1.3335)
			(end -0.5842 -1.3335)
			(stroke
				(width 0)
				(type default)
			)
			(fill no)
			(layer "B.CrtYd")
		)
		(fp_rect
			(start 0.5842 1.3335)
			(end -0.5842 -1.3335)
			(stroke
				(width 0)
				(type default)
			)
			(fill no)
			(layer "B.Fab")
		)
		(pad "1" smd custom
			(at 0 -0.762 180)
			(size 0.2159 0.2159)
			(layers "B.Cu" "B.Mask" "B.Paste")
			(net "P0V975")
			(options
				(clearance outline)
				(anchor circle)
			)
			(primitives
				(gr_poly
					(pts
						(arc
							(start -0.3302 0.4318)
							(mid -0.402042 0.402042)
							(end -0.4318 0.3302)
						)
						(arc
							(start -0.4318 -0.3302)
							(mid -0.402042 -0.402042)
							(end -0.3302 -0.4318)
						)
						(arc
							(start 0.3302 -0.4318)
							(mid 0.402042 -0.402042)
							(end 0.4318 -0.3302)
						)
						(arc
							(start 0.4318 0.3302)
							(mid 0.402042 0.402042)
							(end 0.3302 0.4318)
						)
					)
					(width 0)
					(fill yes)
				)
			)
		)
		(pad "2" smd custom
			(at 0 0.762 180)
			(size 0.2159 0.2159)
			(layers "B.Cu" "B.Mask" "B.Paste")
			(net "PCE_AVDD")
			(options
				(clearance outline)
				(anchor circle)
			)
			(primitives
				(gr_poly
					(pts
						(arc
							(start -0.3302 0.4318)
							(mid -0.402042 0.402042)
							(end -0.4318 0.3302)
						)
						(arc
							(start -0.4318 -0.3302)
							(mid -0.402042 -0.402042)
							(end -0.3302 -0.4318)
						)
						(arc
							(start 0.3302 -0.4318)
							(mid 0.402042 -0.402042)
							(end 0.4318 -0.3302)
						)
						(arc
							(start 0.4318 0.3302)
							(mid 0.402042 0.402042)
							(end 0.3302 0.4318)
						)
					)
					(width 0)
					(fill yes)
				)
			)
		)
	)
	(footprint ""
		(layer "B.Cu")
		(at 38.4556 -116.8908 -90)
		(property "Reference" "R341"
			(at 0 0 90)
			(layer "B.SilkS")
			(hide yes)
			(effects
				(font
					(size 1.27 1.27)
				)
				(justify mirror)
			)
		)
		(property "Value" "4K7R2F-GP"
			(at -0.064008 -3.993896 270)
			(unlocked yes)
			(layer "B.Fab")
			(hide yes)
			(effects
				(font
					(size 1.016 1.016)
					(thickness 0.1524)
				)
				(justify mirror)
			)
		)
		(property "Device Type" "R402H16"
			(at -0.064008 -5.517896 270)
			(unlocked yes)
			(layer "B.Fab")
			(hide yes)
			(effects
				(font
					(size 1.016 1.016)
					(thickness 0.1524)
				)
				(justify mirror)
			)
		)
		(duplicate_pad_numbers_are_jumpers no)
		(fp_line
			(start -0.508 -0.9398)
			(end 0.508 -0.9398)
			(stroke
				(width 0.1524)
				(type default)
			)
			(layer "B.SilkS")
		)
		(fp_line
			(start 0.508 -0.9398)
			(end 0.508 0.9398)
			(stroke
				(width 0.1524)
				(type default)
			)
			(layer "B.SilkS")
		)
		(fp_rect
			(start 0.508 0.9398)
			(end -0.508 -0.9398)
			(stroke
				(width 0)
				(type default)
			)
			(fill no)
			(layer "B.CrtYd")
		)
		(fp_rect
			(start 0.508 0.9398)
			(end -0.508 -0.9398)
			(stroke
				(width 0)
				(type default)
			)
			(fill no)
			(layer "B.Fab")
		)
		(pad "1" smd custom
			(at 0 -0.4445 90)
			(size 0.1397 0.1397)
			(layers "B.Cu" "B.Mask" "B.Paste")
			(net "TEMP_3_A2")
			(options
				(clearance outline)
				(anchor circle)
			)
			(primitives
				(gr_poly
					(pts
						(arc
							(start -0.1778 0.2794)
							(mid -0.249642 0.249642)
							(end -0.2794 0.1778)
						)
						(arc
							(start -0.2794 -0.1778)
							(mid -0.249642 -0.249642)
							(end -0.1778 -0.2794)
						)
						(arc
							(start 0.1778 -0.2794)
							(mid 0.249642 -0.249642)
							(end 0.2794 -0.1778)
						)
						(arc
							(start 0.2794 0.1778)
							(mid 0.249642 0.249642)
							(end 0.1778 0.2794)
						)
					)
					(width 0)
					(fill yes)
				)
			)
		)
		(pad "2" smd custom
			(at 0 0.4445 90)
			(size 0.1397 0.1397)
			(layers "B.Cu" "B.Mask" "B.Paste")
			(net "GND")
			(options
				(clearance outline)
				(anchor circle)
			)
			(primitives
				(gr_poly
					(pts
						(arc
							(start -0.1778 0.2794)
							(mid -0.249642 0.249642)
							(end -0.2794 0.1778)
						)
						(arc
							(start -0.2794 -0.1778)
							(mid -0.249642 -0.249642)
							(end -0.1778 -0.2794)
						)
						(arc
							(start 0.1778 -0.2794)
							(mid 0.249642 -0.249642)
							(end 0.2794 -0.1778)
						)
						(arc
							(start 0.2794 0.1778)
							(mid 0.249642 0.249642)
							(end 0.1778 0.2794)
						)
					)
					(width 0)
					(fill yes)
				)
			)
		)
	)
	(footprint ""
		(layer "B.Cu")
		(at 190.8302 -61.6204 90)
		(property "Reference" "C415"
			(at 0 0 90)
			(layer "B.SilkS")
			(hide yes)
			(effects
				(font
					(size 1.27 1.27)
				)
				(justify mirror)
			)
		)
		(property "Value" "SCD1U6D3V1KX-GP"
			(at 2.8321 -1.7399 90)
			(unlocked yes)
			(layer "B.Fab")
			(hide yes)
			(effects
				(font
					(size 1.016 1.016)
					(thickness 0.1524)
				)
				(justify mirror)
			)
		)
		(property "Device Type" "C0201H13"
			(at 2.8321 -3.2639 90)
			(unlocked yes)
			(layer "B.Fab")
			(hide yes)
			(effects
				(font
					(size 1.016 1.016)
					(thickness 0.1524)
				)
				(justify mirror)
			)
		)
		(duplicate_pad_numbers_are_jumpers no)
		(fp_rect
			(start 0.2794 0.6477)
			(end -0.2794 -0.6477)
			(stroke
				(width 0)
				(type default)
			)
			(fill no)
			(layer "B.CrtYd")
		)
		(fp_rect
			(start 0.2794 0.6477)
			(end -0.2794 -0.6477)
			(stroke
				(width 0)
				(type default)
			)
			(fill no)
			(layer "B.Fab")
		)
		(pad "1" smd custom
			(at 0 -0.2794 270)
			(size 0.0762 0.0762)
			(layers "B.Cu" "B.Mask" "B.Paste")
			(net "P0V975")
			(options
				(clearance outline)
				(anchor circle)
			)
			(primitives
				(gr_poly
					(pts
						(arc
							(start 0.1524 0.127)
							(mid 0.137521 0.162921)
							(end 0.1016 0.1778)
						)
						(arc
							(start -0.1016 0.1778)
							(mid -0.137521 0.162921)
							(end -0.1524 0.127)
						)
						(arc
							(start -0.1524 -0.127)
							(mid -0.137521 -0.162921)
							(end -0.1016 -0.1778)
						)
						(arc
							(start 0.1016 -0.1778)
							(mid 0.137521 -0.162921)
							(end 0.1524 -0.127)
						)
					)
					(width 0)
					(fill yes)
				)
			)
		)
		(pad "2" smd custom
			(at 0 0.2794 270)
			(size 0.0762 0.0762)
			(layers "B.Cu" "B.Mask" "B.Paste")
			(net "GND")
			(options
				(clearance outline)
				(anchor circle)
			)
			(primitives
				(gr_poly
					(pts
						(arc
							(start 0.1524 0.127)
							(mid 0.137521 0.162921)
							(end 0.1016 0.1778)
						)
						(arc
							(start -0.1016 0.1778)
							(mid -0.137521 0.162921)
							(end -0.1524 0.127)
						)
						(arc
							(start -0.1524 -0.127)
							(mid -0.137521 -0.162921)
							(end -0.1016 -0.1778)
						)
						(arc
							(start 0.1016 -0.1778)
							(mid 0.137521 -0.162921)
							(end 0.1524 -0.127)
						)
					)
					(width 0)
					(fill yes)
				)
			)
		)
	)
	(footprint ""
		(layer "B.Cu")
		(at 198.28256 -68.33362 -90)
		(property "Reference" "C383"
			(at 0 0 90)
			(layer "B.SilkS")
			(hide yes)
			(effects
				(font
					(size 1.27 1.27)
				)
				(justify mirror)
			)
		)
		(property "Value" "SCD1U6D3V1KX-GP"
			(at 2.8321 -1.7399 270)
			(unlocked yes)
			(layer "B.Fab")
			(hide yes)
			(effects
				(font
					(size 1.016 1.016)
					(thickness 0.1524)
				)
				(justify mirror)
			)
		)
		(property "Device Type" "C0201H13"
			(at 2.8321 -3.2639 270)
			(unlocked yes)
			(layer "B.Fab")
			(hide yes)
			(effects
				(font
					(size 1.016 1.016)
					(thickness 0.1524)
				)
				(justify mirror)
			)
		)
		(duplicate_pad_numbers_are_jumpers no)
		(fp_rect
			(start 0.2794 0.6477)
			(end -0.2794 -0.6477)
			(stroke
				(width 0)
				(type default)
			)
			(fill no)
			(layer "B.CrtYd")
		)
		(fp_rect
			(start 0.2794 0.6477)
			(end -0.2794 -0.6477)
			(stroke
				(width 0)
				(type default)
			)
			(fill no)
			(layer "B.Fab")
		)
		(pad "1" smd custom
			(at 0 -0.2794 90)
			(size 0.0762 0.0762)
			(layers "B.Cu" "B.Mask" "B.Paste")
			(net "SAS0_AVDD")
			(options
				(clearance outline)
				(anchor circle)
			)
			(primitives
				(gr_poly
					(pts
						(arc
							(start 0.1524 0.127)
							(mid 0.137521 0.162921)
							(end 0.1016 0.1778)
						)
						(arc
							(start -0.1016 0.1778)
							(mid -0.137521 0.162921)
							(end -0.1524 0.127)
						)
						(arc
							(start -0.1524 -0.127)
							(mid -0.137521 -0.162921)
							(end -0.1016 -0.1778)
						)
						(arc
							(start 0.1016 -0.1778)
							(mid 0.137521 -0.162921)
							(end 0.1524 -0.127)
						)
					)
					(width 0)
					(fill yes)
				)
			)
		)
		(pad "2" smd custom
			(at 0 0.2794 90)
			(size 0.0762 0.0762)
			(layers "B.Cu" "B.Mask" "B.Paste")
			(net "GND")
			(options
				(clearance outline)
				(anchor circle)
			)
			(primitives
				(gr_poly
					(pts
						(arc
							(start 0.1524 0.127)
							(mid 0.137521 0.162921)
							(end 0.1016 0.1778)
						)
						(arc
							(start -0.1016 0.1778)
							(mid -0.137521 0.162921)
							(end -0.1524 0.127)
						)
						(arc
							(start -0.1524 -0.127)
							(mid -0.137521 -0.162921)
							(end -0.1016 -0.1778)
						)
						(arc
							(start 0.1016 -0.1778)
							(mid 0.137521 -0.162921)
							(end 0.1524 -0.127)
						)
					)
					(width 0)
					(fill yes)
				)
			)
		)
	)
	(footprint ""
		(layer "B.Cu")
		(at 25.89022 -146.418808 90)
		(property "Reference" "C73"
			(at 0 0 90)
			(layer "B.SilkS")
			(hide yes)
			(effects
				(font
					(size 1.27 1.27)
				)
				(justify mirror)
			)
		)
		(property "Value" "SCD1U16V2KX-3GP"
			(at -1.1811 -2.7051 90)
			(unlocked yes)
			(layer "B.Fab")
			(hide yes)
			(effects
				(font
					(size 1.016 1.016)
					(thickness 0.1524)
				)
				(justify mirror)
			)
		)
		(property "Device Type" "C402H22"
			(at -1.1811 -4.2291 90)
			(unlocked yes)
			(layer "B.Fab")
			(hide yes)
			(effects
				(font
					(size 1.016 1.016)
					(thickness 0.1524)
				)
				(justify mirror)
			)
		)
		(duplicate_pad_numbers_are_jumpers no)
		(fp_rect
			(start 0.4318 0.9525)
			(end -0.4318 -0.9525)
			(stroke
				(width 0)
				(type default)
			)
			(fill no)
			(layer "B.CrtYd")
		)
		(fp_rect
			(start 0.4318 0.9525)
			(end -0.4318 -0.9525)
			(stroke
				(width 0)
				(type default)
			)
			(fill no)
			(layer "B.Fab")
		)
		(pad "1" smd custom
			(at 0 -0.4445 270)
			(size 0.1524 0.1524)
			(layers "B.Cu" "B.Mask" "B.Paste")
			(net "GND")
			(options
				(clearance outline)
				(anchor circle)
			)
			(primitives
				(gr_poly
					(pts
						(arc
							(start 0.3048 0.2032)
							(mid 0.275042 0.275042)
							(end 0.2032 0.3048)
						)
						(arc
							(start -0.2032 0.3048)
							(mid -0.275042 0.275042)
							(end -0.3048 0.2032)
						)
						(arc
							(start -0.3048 -0.2032)
							(mid -0.275042 -0.275042)
							(end -0.2032 -0.3048)
						)
						(arc
							(start 0.2032 -0.3048)
							(mid 0.275042 -0.275042)
							(end 0.3048 -0.2032)
						)
					)
					(width 0)
					(fill yes)
				)
			)
		)
		(pad "2" smd custom
			(at 0 0.4445 270)
			(size 0.1524 0.1524)
			(layers "B.Cu" "B.Mask" "B.Paste")
			(net "P1V2_STBY")
			(options
				(clearance outline)
				(anchor circle)
			)
			(primitives
				(gr_poly
					(pts
						(arc
							(start 0.3048 0.2032)
							(mid 0.275042 0.275042)
							(end 0.2032 0.3048)
						)
						(arc
							(start -0.2032 0.3048)
							(mid -0.275042 0.275042)
							(end -0.3048 0.2032)
						)
						(arc
							(start -0.3048 -0.2032)
							(mid -0.275042 -0.275042)
							(end -0.2032 -0.3048)
						)
						(arc
							(start 0.2032 -0.3048)
							(mid 0.275042 -0.275042)
							(end 0.3048 -0.2032)
						)
					)
					(width 0)
					(fill yes)
				)
			)
		)
	)
	(footprint ""
		(layer "B.Cu")
		(at 12.091924 -132.402326 90)
		(property "Reference" "R238"
			(at 0 0 90)
			(layer "B.SilkS")
			(hide yes)
			(effects
				(font
					(size 1.27 1.27)
				)
				(justify mirror)
			)
		)
		(property "Value" "120R2F-GP"
			(at -0.064008 -3.993896 90)
			(unlocked yes)
			(layer "B.Fab")
			(hide yes)
			(effects
				(font
					(size 1.016 1.016)
					(thickness 0.1524)
				)
				(justify mirror)
			)
		)
		(property "Device Type" "R402H16"
			(at -0.064008 -5.517896 90)
			(unlocked yes)
			(layer "B.Fab")
			(hide yes)
			(effects
				(font
					(size 1.016 1.016)
					(thickness 0.1524)
				)
				(justify mirror)
			)
		)
		(duplicate_pad_numbers_are_jumpers no)
		(fp_line
			(start 0.508 -0.9398)
			(end 0.508 0.9398)
			(stroke
				(width 0.1524)
				(type default)
			)
			(layer "B.SilkS")
		)
		(fp_line
			(start -0.508 -0.9398)
			(end 0.508 -0.9398)
			(stroke
				(width 0.1524)
				(type default)
			)
			(layer "B.SilkS")
		)
		(fp_rect
			(start 0.508 0.9398)
			(end -0.508 -0.9398)
			(stroke
				(width 0)
				(type default)
			)
			(fill no)
			(layer "B.CrtYd")
		)
		(fp_rect
			(start 0.508 0.9398)
			(end -0.508 -0.9398)
			(stroke
				(width 0)
				(type default)
			)
			(fill no)
			(layer "B.Fab")
		)
		(pad "1" smd custom
			(at 0 -0.4445 270)
			(size 0.1397 0.1397)
			(layers "B.Cu" "B.Mask" "B.Paste")
			(net "MEMA_2")
			(options
				(clearance outline)
				(anchor circle)
			)
			(primitives
				(gr_poly
					(pts
						(arc
							(start -0.1778 0.2794)
							(mid -0.249642 0.249642)
							(end -0.2794 0.1778)
						)
						(arc
							(start -0.2794 -0.1778)
							(mid -0.249642 -0.249642)
							(end -0.1778 -0.2794)
						)
						(arc
							(start 0.1778 -0.2794)
							(mid 0.249642 -0.249642)
							(end 0.2794 -0.1778)
						)
						(arc
							(start 0.2794 0.1778)
							(mid 0.249642 0.249642)
							(end 0.1778 0.2794)
						)
					)
					(width 0)
					(fill yes)
				)
			)
		)
		(pad "2" smd custom
			(at 0 0.4445 270)
			(size 0.1397 0.1397)
			(layers "B.Cu" "B.Mask" "B.Paste")
			(net "P1V2_STBY")
			(options
				(clearance outline)
				(anchor circle)
			)
			(primitives
				(gr_poly
					(pts
						(arc
							(start -0.1778 0.2794)
							(mid -0.249642 0.249642)
							(end -0.2794 0.1778)
						)
						(arc
							(start -0.2794 -0.1778)
							(mid -0.249642 -0.249642)
							(end -0.1778 -0.2794)
						)
						(arc
							(start 0.1778 -0.2794)
							(mid 0.249642 -0.249642)
							(end 0.2794 -0.1778)
						)
						(arc
							(start 0.2794 0.1778)
							(mid 0.249642 0.249642)
							(end 0.1778 0.2794)
						)
					)
					(width 0)
					(fill yes)
				)
			)
		)
	)
)
